(kicad_pcb
	(version 20260206)
	(generator "pcbnew")
	(generator_version "10.0")
	(general
		(thickness 1.6)
		(legacy_teardrops no)
	)
	(paper "A4")
	(title_block
		(title "peb — Lightning_PEB_BRD.brd")
		(comment 1 "Lightning (Wiwynn / Facebook NVMe JBOF) / footprints 2146-2152 of 2563")
	)
	(layers
		(0 "F.Cu" signal "TOP")
		(4 "In1.Cu" signal "L2GND")
		(6 "In2.Cu" signal "L3")
		(8 "In3.Cu" signal "L4VCC")
		(10 "In4.Cu" signal "L5VCC")
		(12 "In5.Cu" signal "L6")
		(14 "In6.Cu" signal "L7GND")
		(2 "B.Cu" signal "BOTTOM")
		(9 "F.Adhes" user "F.Adhesive")
		(11 "B.Adhes" user "B.Adhesive")
		(13 "F.Paste" user "Package Geometry/Pastemask Top")
		(15 "B.Paste" user "Package Geometry/Pastemask Bottom")
		(5 "F.SilkS" user "Ref Des/Silkscreen Top")
		(7 "B.SilkS" user "Ref Des/Silkscreen Bottom")
		(1 "F.Mask" user "Board Geometry/Soldermask Top")
		(3 "B.Mask" user "Board Geometry/Soldermask Bottom")
		(17 "Dwgs.User" user "User.Drawings")
		(19 "Cmts.User" user "User.Comments")
		(21 "Eco1.User" user "User.Eco1")
		(23 "Eco2.User" user "User.Eco2")
		(25 "Edge.Cuts" user "Board Geometry/Outline")
		(27 "Margin" user)
		(31 "F.CrtYd" user "Package Geometry/Place Bound Top")
		(29 "B.CrtYd" user "Package Geometry/Place Bound Bottom")
		(35 "F.Fab" user "Ref Des/Assembly Top")
		(33 "B.Fab" user "Ref Des/Assembly Bottom")
	)
	(footprint ""
		(layer "B.Cu")
		(at 214.948008 -4.064)
		(property "Reference" "R3710"
			(at 0 0 0)
			(layer "B.SilkS")
			(hide yes)
			(effects
				(font
					(size 1.27 1.27)
				)
				(justify mirror)
			)
		)
		(property "Value" "1KR2F-3-GP"
			(at -0.064008 -3.993896 0)
			(unlocked yes)
			(layer "B.Fab")
			(hide yes)
			(effects
				(font
					(size 1.016 1.016)
					(thickness 0.1524)
				)
				(justify mirror)
			)
		)
		(property "Device Type" "R402H16"
			(at -0.064008 -5.517896 0)
			(unlocked yes)
			(layer "B.Fab")
			(hide yes)
			(effects
				(font
					(size 1.016 1.016)
					(thickness 0.1524)
				)
				(justify mirror)
			)
		)
		(duplicate_pad_numbers_are_jumpers no)
		(fp_line
			(start -0.508 -0.9398)
			(end 0.508 -0.9398)
			(stroke
				(width 0.1524)
				(type default)
			)
			(layer "B.SilkS")
		)
		(fp_line
			(start 0.508 -0.9398)
			(end 0.508 0.9398)
			(stroke
				(width 0.1524)
				(type default)
			)
			(layer "B.SilkS")
		)
		(fp_rect
			(start 0.508 0.9398)
			(end -0.508 -0.9398)
			(stroke
				(width 0)
				(type default)
			)
			(fill no)
			(layer "B.CrtYd")
		)
		(fp_rect
			(start 0.508 0.9398)
			(end -0.508 -0.9398)
			(stroke
				(width 0)
				(type default)
			)
			(fill no)
			(layer "B.Fab")
		)
		(pad "1" smd custom
			(at 0 -0.4445 180)
			(size 0.1397 0.1397)
			(layers "B.Cu" "B.Mask" "B.Paste")
			(net "HOST2_RST_N")
			(options
				(clearance outline)
				(anchor circle)
			)
			(primitives
				(gr_poly
					(pts
						(arc
							(start -0.1778 0.2794)
							(mid -0.249642 0.249642)
							(end -0.2794 0.1778)
						)
						(arc
							(start -0.2794 -0.1778)
							(mid -0.249642 -0.249642)
							(end -0.1778 -0.2794)
						)
						(arc
							(start 0.1778 -0.2794)
							(mid 0.249642 -0.249642)
							(end 0.2794 -0.1778)
						)
						(arc
							(start 0.2794 0.1778)
							(mid 0.249642 0.249642)
							(end 0.1778 0.2794)
						)
					)
					(width 0)
					(fill yes)
				)
			)
		)
		(pad "2" smd custom
			(at 0 0.4445 180)
			(size 0.1397 0.1397)
			(layers "B.Cu" "B.Mask" "B.Paste")
			(net "P3V3_STBY")
			(options
				(clearance outline)
				(anchor circle)
			)
			(primitives
				(gr_poly
					(pts
						(arc
							(start -0.1778 0.2794)
							(mid -0.249642 0.249642)
							(end -0.2794 0.1778)
						)
						(arc
							(start -0.2794 -0.1778)
							(mid -0.249642 -0.249642)
							(end -0.1778 -0.2794)
						)
						(arc
							(start 0.1778 -0.2794)
							(mid 0.249642 -0.249642)
							(end 0.2794 -0.1778)
						)
						(arc
							(start 0.2794 0.1778)
							(mid 0.249642 0.249642)
							(end 0.1778 0.2794)
						)
					)
					(width 0)
					(fill yes)
				)
			)
		)
	)
	(footprint ""
		(layer "B.Cu")
		(at 51.5366 -130.7846 90)
		(property "Reference" "R534"
			(at 0 0 90)
			(layer "B.SilkS")
			(hide yes)
			(effects
				(font
					(size 1.27 1.27)
				)
				(justify mirror)
			)
		)
		(property "Value" "0R2J-2-GP"
			(at -0.064008 -3.993896 90)
			(unlocked yes)
			(layer "B.Fab")
			(hide yes)
			(effects
				(font
					(size 1.016 1.016)
					(thickness 0.1524)
				)
				(justify mirror)
			)
		)
		(property "Device Type" "R402H16"
			(at -0.064008 -5.517896 90)
			(unlocked yes)
			(layer "B.Fab")
			(hide yes)
			(effects
				(font
					(size 1.016 1.016)
					(thickness 0.1524)
				)
				(justify mirror)
			)
		)
		(duplicate_pad_numbers_are_jumpers no)
		(fp_line
			(start 0.508 -0.9398)
			(end 0.508 0.9398)
			(stroke
				(width 0.1524)
				(type default)
			)
			(layer "B.SilkS")
		)
		(fp_line
			(start -0.508 -0.9398)
			(end 0.508 -0.9398)
			(stroke
				(width 0.1524)
				(type default)
			)
			(layer "B.SilkS")
		)
		(fp_rect
			(start 0.508 0.9398)
			(end -0.508 -0.9398)
			(stroke
				(width 0)
				(type default)
			)
			(fill no)
			(layer "B.CrtYd")
		)
		(fp_rect
			(start 0.508 0.9398)
			(end -0.508 -0.9398)
			(stroke
				(width 0)
				(type default)
			)
			(fill no)
			(layer "B.Fab")
		)
		(pad "1" smd custom
			(at 0 -0.4445 270)
			(size 0.1397 0.1397)
			(layers "B.Cu" "B.Mask" "B.Paste")
			(net "BMC_USB1_HDN2")
			(options
				(clearance outline)
				(anchor circle)
			)
			(primitives
				(gr_poly
					(pts
						(arc
							(start -0.1778 0.2794)
							(mid -0.249642 0.249642)
							(end -0.2794 0.1778)
						)
						(arc
							(start -0.2794 -0.1778)
							(mid -0.249642 -0.249642)
							(end -0.1778 -0.2794)
						)
						(arc
							(start 0.1778 -0.2794)
							(mid 0.249642 -0.249642)
							(end 0.2794 -0.1778)
						)
						(arc
							(start 0.2794 0.1778)
							(mid 0.249642 0.249642)
							(end 0.1778 0.2794)
						)
					)
					(width 0)
					(fill yes)
				)
			)
		)
		(pad "2" smd custom
			(at 0 0.4445 270)
			(size 0.1397 0.1397)
			(layers "B.Cu" "B.Mask" "B.Paste")
			(net "USB_P4_DN_BMC")
			(options
				(clearance outline)
				(anchor circle)
			)
			(primitives
				(gr_poly
					(pts
						(arc
							(start -0.1778 0.2794)
							(mid -0.249642 0.249642)
							(end -0.2794 0.1778)
						)
						(arc
							(start -0.2794 -0.1778)
							(mid -0.249642 -0.249642)
							(end -0.1778 -0.2794)
						)
						(arc
							(start 0.1778 -0.2794)
							(mid 0.249642 -0.249642)
							(end 0.2794 -0.1778)
						)
						(arc
							(start 0.2794 0.1778)
							(mid 0.249642 0.249642)
							(end 0.1778 0.2794)
						)
					)
					(width 0)
					(fill yes)
				)
			)
		)
	)
	(footprint ""
		(layer "B.Cu")
		(at 41.656 -131.064 -90)
		(property "Reference" "C214"
			(at 0 0 90)
			(layer "B.SilkS")
			(hide yes)
			(effects
				(font
					(size 1.27 1.27)
				)
				(justify mirror)
			)
		)
		(property "Value" "SC1U10V2KX-4-GP"
			(at -1.1811 -2.7051 270)
			(unlocked yes)
			(layer "B.Fab")
			(hide yes)
			(effects
				(font
					(size 1.016 1.016)
					(thickness 0.1524)
				)
				(justify mirror)
			)
		)
		(property "Device Type" "C402H22"
			(at -1.1811 -4.2291 270)
			(unlocked yes)
			(layer "B.Fab")
			(hide yes)
			(effects
				(font
					(size 1.016 1.016)
					(thickness 0.1524)
				)
				(justify mirror)
			)
		)
		(duplicate_pad_numbers_are_jumpers no)
		(fp_rect
			(start 0.4318 0.9525)
			(end -0.4318 -0.9525)
			(stroke
				(width 0)
				(type default)
			)
			(fill no)
			(layer "B.CrtYd")
		)
		(fp_rect
			(start 0.4318 0.9525)
			(end -0.4318 -0.9525)
			(stroke
				(width 0)
				(type default)
			)
			(fill no)
			(layer "B.Fab")
		)
		(pad "1" smd custom
			(at 0 -0.4445 90)
			(size 0.1524 0.1524)
			(layers "B.Cu" "B.Mask" "B.Paste")
			(net "P3V3_STBY")
			(options
				(clearance outline)
				(anchor circle)
			)
			(primitives
				(gr_poly
					(pts
						(arc
							(start 0.3048 0.2032)
							(mid 0.275042 0.275042)
							(end 0.2032 0.3048)
						)
						(arc
							(start -0.2032 0.3048)
							(mid -0.275042 0.275042)
							(end -0.3048 0.2032)
						)
						(arc
							(start -0.3048 -0.2032)
							(mid -0.275042 -0.275042)
							(end -0.2032 -0.3048)
						)
						(arc
							(start 0.2032 -0.3048)
							(mid 0.275042 -0.275042)
							(end 0.3048 -0.2032)
						)
					)
					(width 0)
					(fill yes)
				)
			)
		)
		(pad "2" smd custom
			(at 0 0.4445 90)
			(size 0.1524 0.1524)
			(layers "B.Cu" "B.Mask" "B.Paste")
			(net "GND")
			(options
				(clearance outline)
				(anchor circle)
			)
			(primitives
				(gr_poly
					(pts
						(arc
							(start 0.3048 0.2032)
							(mid 0.275042 0.275042)
							(end 0.2032 0.3048)
						)
						(arc
							(start -0.2032 0.3048)
							(mid -0.275042 0.275042)
							(end -0.3048 0.2032)
						)
						(arc
							(start -0.3048 -0.2032)
							(mid -0.275042 -0.275042)
							(end -0.2032 -0.3048)
						)
						(arc
							(start 0.2032 -0.3048)
							(mid 0.275042 -0.275042)
							(end 0.3048 -0.2032)
						)
					)
					(width 0)
					(fill yes)
				)
			)
		)
	)
	(footprint ""
		(layer "B.Cu")
		(at 20.955 -136.779 90)
		(property "Reference" "R606"
			(at 0 0 90)
			(layer "B.SilkS")
			(hide yes)
			(effects
				(font
					(size 1.27 1.27)
				)
				(justify mirror)
			)
		)
		(property "Value" "22R2F-1-GP"
			(at -0.064008 -3.993896 90)
			(unlocked yes)
			(layer "B.Fab")
			(hide yes)
			(effects
				(font
					(size 1.016 1.016)
					(thickness 0.1524)
				)
				(justify mirror)
			)
		)
		(property "Device Type" "R402H16"
			(at -0.064008 -5.517896 90)
			(unlocked yes)
			(layer "B.Fab")
			(hide yes)
			(effects
				(font
					(size 1.016 1.016)
					(thickness 0.1524)
				)
				(justify mirror)
			)
		)
		(duplicate_pad_numbers_are_jumpers no)
		(fp_line
			(start 0.508 -0.9398)
			(end 0.508 0.9398)
			(stroke
				(width 0.1524)
				(type default)
			)
			(layer "B.SilkS")
		)
		(fp_line
			(start -0.508 -0.9398)
			(end 0.508 -0.9398)
			(stroke
				(width 0.1524)
				(type default)
			)
			(layer "B.SilkS")
		)
		(fp_rect
			(start 0.508 0.9398)
			(end -0.508 -0.9398)
			(stroke
				(width 0)
				(type default)
			)
			(fill no)
			(layer "B.CrtYd")
		)
		(fp_rect
			(start 0.508 0.9398)
			(end -0.508 -0.9398)
			(stroke
				(width 0)
				(type default)
			)
			(fill no)
			(layer "B.Fab")
		)
		(pad "1" smd custom
			(at 0 -0.4445 270)
			(size 0.1397 0.1397)
			(layers "B.Cu" "B.Mask" "B.Paste")
			(net "ROMD1_R")
			(options
				(clearance outline)
				(anchor circle)
			)
			(primitives
				(gr_poly
					(pts
						(arc
							(start -0.1778 0.2794)
							(mid -0.249642 0.249642)
							(end -0.2794 0.1778)
						)
						(arc
							(start -0.2794 -0.1778)
							(mid -0.249642 -0.249642)
							(end -0.1778 -0.2794)
						)
						(arc
							(start 0.1778 -0.2794)
							(mid 0.249642 -0.249642)
							(end 0.2794 -0.1778)
						)
						(arc
							(start 0.2794 0.1778)
							(mid 0.249642 0.249642)
							(end 0.1778 0.2794)
						)
					)
					(width 0)
					(fill yes)
				)
			)
		)
		(pad "2" smd custom
			(at 0 0.4445 270)
			(size 0.1397 0.1397)
			(layers "B.Cu" "B.Mask" "B.Paste")
			(net "ROMD1")
			(options
				(clearance outline)
				(anchor circle)
			)
			(primitives
				(gr_poly
					(pts
						(arc
							(start -0.1778 0.2794)
							(mid -0.249642 0.249642)
							(end -0.2794 0.1778)
						)
						(arc
							(start -0.2794 -0.1778)
							(mid -0.249642 -0.249642)
							(end -0.1778 -0.2794)
						)
						(arc
							(start 0.1778 -0.2794)
							(mid 0.249642 -0.249642)
							(end 0.2794 -0.1778)
						)
						(arc
							(start 0.2794 0.1778)
							(mid 0.249642 0.249642)
							(end 0.1778 0.2794)
						)
					)
					(width 0)
					(fill yes)
				)
			)
		)
	)
	(footprint ""
		(layer "B.Cu")
		(at 155.454604 -33.592008)
		(property "Reference" "R2931"
			(at 0 0 0)
			(layer "B.SilkS")
			(hide yes)
			(effects
				(font
					(size 1.27 1.27)
				)
				(justify mirror)
			)
		)
		(property "Value" "0R2J-2-GP"
			(at -0.064008 -3.993896 0)
			(unlocked yes)
			(layer "B.Fab")
			(hide yes)
			(effects
				(font
					(size 1.016 1.016)
					(thickness 0.1524)
				)
				(justify mirror)
			)
		)
		(property "Device Type" "R402H16"
			(at -0.064008 -5.517896 0)
			(unlocked yes)
			(layer "B.Fab")
			(hide yes)
			(effects
				(font
					(size 1.016 1.016)
					(thickness 0.1524)
				)
				(justify mirror)
			)
		)
		(duplicate_pad_numbers_are_jumpers no)
		(fp_line
			(start -0.508 -0.9398)
			(end 0.508 -0.9398)
			(stroke
				(width 0.1524)
				(type default)
			)
			(layer "B.SilkS")
		)
		(fp_line
			(start 0.508 -0.9398)
			(end 0.508 0.9398)
			(stroke
				(width 0.1524)
				(type default)
			)
			(layer "B.SilkS")
		)
		(fp_rect
			(start 0.508 0.9398)
			(end -0.508 -0.9398)
			(stroke
				(width 0)
				(type default)
			)
			(fill no)
			(layer "B.CrtYd")
		)
		(fp_rect
			(start 0.508 0.9398)
			(end -0.508 -0.9398)
			(stroke
				(width 0)
				(type default)
			)
			(fill no)
			(layer "B.Fab")
		)
		(pad "1" smd custom
			(at 0 -0.4445 180)
			(size 0.1397 0.1397)
			(layers "B.Cu" "B.Mask" "B.Paste")
			(net "CBL_PRSNT_N_3")
			(options
				(clearance outline)
				(anchor circle)
			)
			(primitives
				(gr_poly
					(pts
						(arc
							(start -0.1778 0.2794)
							(mid -0.249642 0.249642)
							(end -0.2794 0.1778)
						)
						(arc
							(start -0.2794 -0.1778)
							(mid -0.249642 -0.249642)
							(end -0.1778 -0.2794)
						)
						(arc
							(start 0.1778 -0.2794)
							(mid 0.249642 -0.249642)
							(end 0.2794 -0.1778)
						)
						(arc
							(start 0.2794 0.1778)
							(mid 0.249642 0.249642)
							(end 0.1778 0.2794)
						)
					)
					(width 0)
					(fill yes)
				)
			)
		)
		(pad "2" smd custom
			(at 0 0.4445 180)
			(size 0.1397 0.1397)
			(layers "B.Cu" "B.Mask" "B.Paste")
			(net "8644_SDA_R_3")
			(options
				(clearance outline)
				(anchor circle)
			)
			(primitives
				(gr_poly
					(pts
						(arc
							(start -0.1778 0.2794)
							(mid -0.249642 0.249642)
							(end -0.2794 0.1778)
						)
						(arc
							(start -0.2794 -0.1778)
							(mid -0.249642 -0.249642)
							(end -0.1778 -0.2794)
						)
						(arc
							(start 0.1778 -0.2794)
							(mid 0.249642 -0.249642)
							(end 0.2794 -0.1778)
						)
						(arc
							(start 0.2794 0.1778)
							(mid 0.249642 0.249642)
							(end 0.1778 0.2794)
						)
					)
					(width 0)
					(fill yes)
				)
			)
		)
	)
	(footprint ""
		(layer "B.Cu")
		(at 182.9054 -10.1092)
		(property "Reference" "R250"
			(at 0 0 0)
			(layer "B.SilkS")
			(hide yes)
			(effects
				(font
					(size 1.27 1.27)
				)
				(justify mirror)
			)
		)
		(property "Value" "4K7R2F-GP"
			(at -0.064008 -3.993896 0)
			(unlocked yes)
			(layer "B.Fab")
			(hide yes)
			(effects
				(font
					(size 1.016 1.016)
					(thickness 0.1524)
				)
				(justify mirror)
			)
		)
		(property "Device Type" "R402H16"
			(at -0.064008 -5.517896 0)
			(unlocked yes)
			(layer "B.Fab")
			(hide yes)
			(effects
				(font
					(size 1.016 1.016)
					(thickness 0.1524)
				)
				(justify mirror)
			)
		)
		(duplicate_pad_numbers_are_jumpers no)
		(fp_line
			(start -0.508 -0.9398)
			(end 0.508 -0.9398)
			(stroke
				(width 0.1524)
				(type default)
			)
			(layer "B.SilkS")
		)
		(fp_line
			(start 0.508 -0.9398)
			(end 0.508 0.9398)
			(stroke
				(width 0.1524)
				(type default)
			)
			(layer "B.SilkS")
		)
		(fp_rect
			(start 0.508 0.9398)
			(end -0.508 -0.9398)
			(stroke
				(width 0)
				(type default)
			)
			(fill no)
			(layer "B.CrtYd")
		)
		(fp_rect
			(start 0.508 0.9398)
			(end -0.508 -0.9398)
			(stroke
				(width 0)
				(type default)
			)
			(fill no)
			(layer "B.Fab")
		)
		(pad "1" smd custom
			(at 0 -0.4445 180)
			(size 0.1397 0.1397)
			(layers "B.Cu" "B.Mask" "B.Paste")
			(net "P3V3_STBY")
			(options
				(clearance outline)
				(anchor circle)
			)
			(primitives
				(gr_poly
					(pts
						(arc
							(start -0.1778 0.2794)
							(mid -0.249642 0.249642)
							(end -0.2794 0.1778)
						)
						(arc
							(start -0.2794 -0.1778)
							(mid -0.249642 -0.249642)
							(end -0.1778 -0.2794)
						)
						(arc
							(start 0.1778 -0.2794)
							(mid 0.249642 -0.249642)
							(end 0.2794 -0.1778)
						)
						(arc
							(start 0.2794 0.1778)
							(mid 0.249642 0.249642)
							(end 0.1778 0.2794)
						)
					)
					(width 0)
					(fill yes)
				)
			)
		)
		(pad "2" smd custom
			(at 0 0.4445 180)
			(size 0.1397 0.1397)
			(layers "B.Cu" "B.Mask" "B.Paste")
			(net "CLK_P_3_R")
			(options
				(clearance outline)
				(anchor circle)
			)
			(primitives
				(gr_poly
					(pts
						(arc
							(start -0.1778 0.2794)
							(mid -0.249642 0.249642)
							(end -0.2794 0.1778)
						)
						(arc
							(start -0.2794 -0.1778)
							(mid -0.249642 -0.249642)
							(end -0.1778 -0.2794)
						)
						(arc
							(start 0.1778 -0.2794)
							(mid 0.249642 -0.249642)
							(end 0.2794 -0.1778)
						)
						(arc
							(start 0.2794 0.1778)
							(mid 0.249642 0.249642)
							(end 0.1778 0.2794)
						)
					)
					(width 0)
					(fill yes)
				)
			)
		)
	)
	(footprint ""
		(layer "B.Cu")
		(at 75.832716 -183.238902)
		(property "Reference" "R4107"
			(at 0 0 0)
			(layer "B.SilkS")
			(hide yes)
			(effects
				(font
					(size 1.27 1.27)
				)
				(justify mirror)
			)
		)
		(property "Value" "4K7R2F-GP"
			(at -0.064008 -3.993896 0)
			(unlocked yes)
			(layer "B.Fab")
			(hide yes)
			(effects
				(font
					(size 1.016 1.016)
					(thickness 0.1524)
				)
				(justify mirror)
			)
		)
		(property "Device Type" "R402H16"
			(at -0.064008 -5.517896 0)
			(unlocked yes)
			(layer "B.Fab")
			(hide yes)
			(effects
				(font
					(size 1.016 1.016)
					(thickness 0.1524)
				)
				(justify mirror)
			)
		)
		(duplicate_pad_numbers_are_jumpers no)
		(fp_line
			(start -0.508 -0.9398)
			(end 0.508 -0.9398)
			(stroke
				(width 0.1524)
				(type default)
			)
			(layer "B.SilkS")
		)
		(fp_line
			(start 0.508 -0.9398)
			(end 0.508 0.9398)
			(stroke
				(width 0.1524)
				(type default)
			)
			(layer "B.SilkS")
		)
		(fp_rect
			(start 0.508 0.9398)
			(end -0.508 -0.9398)
			(stroke
				(width 0)
				(type default)
			)
			(fill no)
			(layer "B.CrtYd")
		)
		(fp_rect
			(start 0.508 0.9398)
			(end -0.508 -0.9398)
			(stroke
				(width 0)
				(type default)
			)
			(fill no)
			(layer "B.Fab")
		)
		(pad "1" smd custom
			(at 0 -0.4445 180)
			(size 0.1397 0.1397)
			(layers "B.Cu" "B.Mask" "B.Paste")
			(net "SSD_PRSNT#5")
			(options
				(clearance outline)
				(anchor circle)
			)
			(primitives
				(gr_poly
					(pts
						(arc
							(start -0.1778 0.2794)
							(mid -0.249642 0.249642)
							(end -0.2794 0.1778)
						)
						(arc
							(start -0.2794 -0.1778)
							(mid -0.249642 -0.249642)
							(end -0.1778 -0.2794)
						)
						(arc
							(start 0.1778 -0.2794)
							(mid 0.249642 -0.249642)
							(end 0.2794 -0.1778)
						)
						(arc
							(start 0.2794 0.1778)
							(mid 0.249642 0.249642)
							(end 0.1778 0.2794)
						)
					)
					(width 0)
					(fill yes)
				)
			)
		)
		(pad "2" smd custom
			(at 0 0.4445 180)
			(size 0.1397 0.1397)
			(layers "B.Cu" "B.Mask" "B.Paste")
			(net "P3V3_STBY")
			(options
				(clearance outline)
				(anchor circle)
			)
			(primitives
				(gr_poly
					(pts
						(arc
							(start -0.1778 0.2794)
							(mid -0.249642 0.249642)
							(end -0.2794 0.1778)
						)
						(arc
							(start -0.2794 -0.1778)
							(mid -0.249642 -0.249642)
							(end -0.1778 -0.2794)
						)
						(arc
							(start 0.1778 -0.2794)
							(mid 0.249642 -0.249642)
							(end 0.2794 -0.1778)
						)
						(arc
							(start 0.2794 0.1778)
							(mid 0.249642 0.249642)
							(end 0.1778 0.2794)
						)
					)
					(width 0)
					(fill yes)
				)
			)
		)
	)
)
